(kicad_pcb
	(version 20260206)
	(generator "pcbnew")
	(generator_version "10.0")
	(general
		(thickness 1.6)
		(legacy_teardrops no)
	)
	(paper "A4")
	(title_block
		(title "9052_F0T_PDB_Converter_Brick_F_V03_1208_1600_OCP.brd")
		(comment 1 "Grand Teton / footprints 286-293 of 578")
	)
	(layers
		(0 "F.Cu" signal "TOP")
		(4 "In1.Cu" signal "GND")
		(6 "In2.Cu" signal "IN1")
		(8 "In3.Cu" signal "GND1")
		(10 "In4.Cu" signal "VCC")
		(12 "In5.Cu" signal "VCC1")
		(14 "In6.Cu" signal "GND2")
		(16 "In7.Cu" signal "IN2")
		(18 "In8.Cu" signal "GND3")
		(2 "B.Cu" signal "BOTTOM")
		(9 "F.Adhes" user "F.Adhesive")
		(11 "B.Adhes" user "B.Adhesive")
		(13 "F.Paste" user "Package Geometry/Pastemask Top")
		(15 "B.Paste" user "Package Geometry/Pastemask Bottom")
		(5 "F.SilkS" user "Ref Des/Silkscreen Top")
		(7 "B.SilkS" user "Ref Des/Silkscreen Bottom")
		(1 "F.Mask" user "Board Geometry/Soldermask Top")
		(3 "B.Mask" user "Board Geometry/Soldermask Bottom")
		(17 "Dwgs.User" user "User.Drawings")
		(19 "Cmts.User" user "User.Comments")
		(21 "Eco1.User" user "User.Eco1")
		(23 "Eco2.User" user "User.Eco2")
		(25 "Edge.Cuts" user "Board Geometry/Outline")
		(27 "Margin" user)
		(31 "F.CrtYd" user "Package Geometry/Place Bound Top")
		(29 "B.CrtYd" user "Package Geometry/Place Bound Bottom")
		(35 "F.Fab" user "Ref Des/Assembly Top")
		(33 "B.Fab" user "Ref Des/Assembly Bottom")
	)
	(footprint ""
		(layer "F.Cu")
		(at 184.52846 -51.816)
		(property "Reference" "PC128"
			(at 0 0 0)
			(layer "F.SilkS")
			(hide yes)
			(effects
				(font
					(size 1.27 1.27)
				)
			)
		)
		(property "Value" ""
			(at 0 0 0)
			(layer "F.Fab")
			(effects
				(font
					(size 1.27 1.27)
				)
			)
		)
		(duplicate_pad_numbers_are_jumpers no)
		(fp_line
			(start -1.524 -0.762)
			(end 1.524 -0.762)
			(stroke
				(width 0.1524)
				(type default)
			)
			(layer "F.SilkS")
		)
		(fp_line
			(start -1.524 0.762)
			(end -1.524 -0.762)
			(stroke
				(width 0.1524)
				(type default)
			)
			(layer "F.SilkS")
		)
		(fp_line
			(start 1.524 -0.762)
			(end 1.524 0.762)
			(stroke
				(width 0.1524)
				(type default)
			)
			(layer "F.SilkS")
		)
		(fp_line
			(start 1.524 0.762)
			(end -1.524 0.762)
			(stroke
				(width 0.1524)
				(type default)
			)
			(layer "F.SilkS")
		)
		(fp_line
			(start -1.1049 -0.724916)
			(end -1.1049 0.724916)
			(stroke
				(width 0.1)
				(type default)
			)
			(layer "F.Fab")
		)
		(fp_line
			(start -1.1049 0.724916)
			(end 1.1049 0.724916)
			(stroke
				(width 0.1)
				(type default)
			)
			(layer "F.Fab")
		)
		(fp_line
			(start 1.1049 -0.724916)
			(end -1.1049 -0.724916)
			(stroke
				(width 0.1)
				(type default)
			)
			(layer "F.Fab")
		)
		(fp_line
			(start 1.1049 0.724916)
			(end 1.1049 -0.724916)
			(stroke
				(width 0.1)
				(type default)
			)
			(layer "F.Fab")
		)
		(pad "1" smd rect
			(at -0.889 0 180)
			(size 1.016 1.27)
			(layers "F.Cu" "F.Mask" "F.Paste")
			(net "P12V_BRICK")
		)
		(pad "2" smd rect
			(at 0.889 0 180)
			(size 1.016 1.27)
			(layers "F.Cu" "F.Mask" "F.Paste")
			(net "GND")
		)
	)
	(footprint ""
		(layer "F.Cu")
		(at 96.905826 -130.175)
		(property "Reference" "PC48"
			(at 0 0 0)
			(layer "F.SilkS")
			(hide yes)
			(effects
				(font
					(size 1.27 1.27)
				)
			)
		)
		(property "Value" ""
			(at 0 0 0)
			(layer "F.Fab")
			(effects
				(font
					(size 1.27 1.27)
				)
			)
		)
		(duplicate_pad_numbers_are_jumpers no)
		(fp_line
			(start -2.2098 -0.9398)
			(end 2.2098 -0.9398)
			(stroke
				(width 0.1524)
				(type default)
			)
			(layer "F.SilkS")
		)
		(fp_line
			(start -2.2098 0.9398)
			(end -2.2098 -0.9398)
			(stroke
				(width 0.1524)
				(type default)
			)
			(layer "F.SilkS")
		)
		(fp_line
			(start 2.2098 -0.9398)
			(end 2.2098 0.9398)
			(stroke
				(width 0.1524)
				(type default)
			)
			(layer "F.SilkS")
		)
		(fp_line
			(start 2.2098 0.9398)
			(end -2.2098 0.9398)
			(stroke
				(width 0.1524)
				(type default)
			)
			(layer "F.SilkS")
		)
		(fp_line
			(start -1.700022 -0.899922)
			(end 1.700022 -0.899922)
			(stroke
				(width 0.1)
				(type default)
			)
			(layer "F.Fab")
		)
		(fp_line
			(start -1.700022 0.899922)
			(end -1.700022 -0.899922)
			(stroke
				(width 0.1)
				(type default)
			)
			(layer "F.Fab")
		)
		(fp_line
			(start 1.700022 -0.899922)
			(end 1.700022 0.899922)
			(stroke
				(width 0.1)
				(type default)
			)
			(layer "F.Fab")
		)
		(fp_line
			(start 1.700022 0.899922)
			(end -1.700022 0.899922)
			(stroke
				(width 0.1)
				(type default)
			)
			(layer "F.Fab")
		)
		(pad "1" smd rect
			(at -1.4732 0 180)
			(size 1.1684 1.5748)
			(layers "F.Cu" "F.Mask" "F.Paste")
			(net "P52V_HS_FILTER")
		)
		(pad "2" smd rect
			(at 1.4732 0 180)
			(size 1.1684 1.5748)
			(layers "F.Cu" "F.Mask" "F.Paste")
			(net "GND")
		)
	)
	(footprint ""
		(layer "F.Cu")
		(at 271.412716 -33.849818 -90)
		(property "Reference" "PC487"
			(at 0 0 270)
			(layer "F.SilkS")
			(hide yes)
			(effects
				(font
					(size 1.27 1.27)
				)
			)
		)
		(property "Value" ""
			(at 0 0 270)
			(layer "F.Fab")
			(effects
				(font
					(size 1.27 1.27)
				)
			)
		)
		(duplicate_pad_numbers_are_jumpers no)
		(fp_line
			(start -2.2098 0.9398)
			(end -2.2098 -0.9398)
			(stroke
				(width 0.1524)
				(type default)
			)
			(layer "F.SilkS")
		)
		(fp_line
			(start 2.2098 0.9398)
			(end -2.2098 0.9398)
			(stroke
				(width 0.1524)
				(type default)
			)
			(layer "F.SilkS")
		)
		(fp_line
			(start -2.2098 -0.9398)
			(end 2.2098 -0.9398)
			(stroke
				(width 0.1524)
				(type default)
			)
			(layer "F.SilkS")
		)
		(fp_line
			(start 2.2098 -0.9398)
			(end 2.2098 0.9398)
			(stroke
				(width 0.1524)
				(type default)
			)
			(layer "F.SilkS")
		)
		(fp_line
			(start -1.700022 0.899922)
			(end -1.700022 -0.899922)
			(stroke
				(width 0.1)
				(type default)
			)
			(layer "F.Fab")
		)
		(fp_line
			(start 1.700022 0.899922)
			(end -1.700022 0.899922)
			(stroke
				(width 0.1)
				(type default)
			)
			(layer "F.Fab")
		)
		(fp_line
			(start -1.700022 -0.899922)
			(end 1.700022 -0.899922)
			(stroke
				(width 0.1)
				(type default)
			)
			(layer "F.Fab")
		)
		(fp_line
			(start 1.700022 -0.899922)
			(end 1.700022 0.899922)
			(stroke
				(width 0.1)
				(type default)
			)
			(layer "F.Fab")
		)
		(pad "1" smd rect
			(at -1.4732 0 90)
			(size 1.1684 1.5748)
			(layers "F.Cu" "F.Mask" "F.Paste")
			(net "P52V_HS1_DVCC")
		)
		(pad "2" smd rect
			(at 1.4732 0 90)
			(size 1.1684 1.5748)
			(layers "F.Cu" "F.Mask" "F.Paste")
			(net "GND")
		)
	)
	(footprint ""
		(layer "F.Cu")
		(at 239.395 -95.504 -90)
		(property "Reference" "C43"
			(at 0 0 270)
			(layer "F.SilkS")
			(hide yes)
			(effects
				(font
					(size 1.27 1.27)
				)
			)
		)
		(property "Value" ""
			(at 0 0 270)
			(layer "F.Fab")
			(effects
				(font
					(size 1.27 1.27)
				)
			)
		)
		(duplicate_pad_numbers_are_jumpers no)
		(fp_line
			(start -2.2098 0.9398)
			(end -2.2098 -0.9398)
			(stroke
				(width 0.1524)
				(type default)
			)
			(layer "F.SilkS")
		)
		(fp_line
			(start 2.2098 0.9398)
			(end -2.2098 0.9398)
			(stroke
				(width 0.1524)
				(type default)
			)
			(layer "F.SilkS")
		)
		(fp_line
			(start -2.2098 -0.9398)
			(end 2.2098 -0.9398)
			(stroke
				(width 0.1524)
				(type default)
			)
			(layer "F.SilkS")
		)
		(fp_line
			(start 2.2098 -0.9398)
			(end 2.2098 0.9398)
			(stroke
				(width 0.1524)
				(type default)
			)
			(layer "F.SilkS")
		)
		(fp_line
			(start -1.700022 0.899922)
			(end -1.700022 -0.899922)
			(stroke
				(width 0.1)
				(type default)
			)
			(layer "F.Fab")
		)
		(fp_line
			(start 1.700022 0.899922)
			(end -1.700022 0.899922)
			(stroke
				(width 0.1)
				(type default)
			)
			(layer "F.Fab")
		)
		(fp_line
			(start -1.700022 -0.899922)
			(end 1.700022 -0.899922)
			(stroke
				(width 0.1)
				(type default)
			)
			(layer "F.Fab")
		)
		(fp_line
			(start 1.700022 -0.899922)
			(end 1.700022 0.899922)
			(stroke
				(width 0.1)
				(type default)
			)
			(layer "F.Fab")
		)
		(pad "1" smd rect
			(at -1.4732 0 90)
			(size 1.1684 1.5748)
			(layers "F.Cu" "F.Mask" "F.Paste")
			(net "P52V_HS")
		)
		(pad "2" smd rect
			(at 1.4732 0 90)
			(size 1.1684 1.5748)
			(layers "F.Cu" "F.Mask" "F.Paste")
			(net "GND")
		)
	)
	(footprint ""
		(layer "F.Cu")
		(at 270.383 -117.688868 -90)
		(property "Reference" "PR12"
			(at 0 0 270)
			(layer "F.SilkS")
			(hide yes)
			(effects
				(font
					(size 1.27 1.27)
				)
			)
		)
		(property "Value" ""
			(at 0 0 270)
			(layer "F.Fab")
			(effects
				(font
					(size 1.27 1.27)
				)
			)
		)
		(duplicate_pad_numbers_are_jumpers no)
		(fp_line
			(start -1.2954 0.5842)
			(end -1.2954 -0.5842)
			(stroke
				(width 0.1524)
				(type default)
			)
			(layer "F.SilkS")
		)
		(fp_line
			(start 1.2954 0.5842)
			(end -1.2954 0.5842)
			(stroke
				(width 0.1524)
				(type default)
			)
			(layer "F.SilkS")
		)
		(fp_line
			(start -1.2954 -0.5842)
			(end 1.2954 -0.5842)
			(stroke
				(width 0.1524)
				(type default)
			)
			(layer "F.SilkS")
		)
		(fp_line
			(start 1.2954 -0.5842)
			(end 1.2954 0.5842)
			(stroke
				(width 0.1524)
				(type default)
			)
			(layer "F.SilkS")
		)
		(fp_line
			(start -0.8636 0.4572)
			(end -0.8636 0.4318)
			(stroke
				(width 0.1)
				(type default)
			)
			(layer "F.Fab")
		)
		(fp_line
			(start 0.8636 0.4572)
			(end -0.8636 0.4572)
			(stroke
				(width 0.1)
				(type default)
			)
			(layer "F.Fab")
		)
		(fp_line
			(start -0.8636 0.4318)
			(end -0.8636 0.4064)
			(stroke
				(width 0.1)
				(type default)
			)
			(layer "F.Fab")
		)
		(fp_line
			(start -1.1938 0.4064)
			(end -1.1938 -0.406654)
			(stroke
				(width 0.1)
				(type default)
			)
			(layer "F.Fab")
		)
		(fp_line
			(start -0.8636 0.4064)
			(end -1.1938 0.4064)
			(stroke
				(width 0.1)
				(type default)
			)
			(layer "F.Fab")
		)
		(fp_line
			(start 0.8636 0.4064)
			(end 0.8636 0.4572)
			(stroke
				(width 0.1)
				(type default)
			)
			(layer "F.Fab")
		)
		(fp_line
			(start 1.1938 0.4064)
			(end 0.8636 0.4064)
			(stroke
				(width 0.1)
				(type default)
			)
			(layer "F.Fab")
		)
		(fp_line
			(start -1.1938 -0.406654)
			(end -0.8636 -0.406654)
			(stroke
				(width 0.1)
				(type default)
			)
			(layer "F.Fab")
		)
		(fp_line
			(start -0.8636 -0.406654)
			(end -0.8636 -0.4572)
			(stroke
				(width 0.1)
				(type default)
			)
			(layer "F.Fab")
		)
		(fp_line
			(start 0.8636 -0.406654)
			(end 1.1938 -0.406654)
			(stroke
				(width 0.1)
				(type default)
			)
			(layer "F.Fab")
		)
		(fp_line
			(start 1.1938 -0.406654)
			(end 1.1938 0.4064)
			(stroke
				(width 0.1)
				(type default)
			)
			(layer "F.Fab")
		)
		(fp_line
			(start -0.8636 -0.4572)
			(end 0.8636 -0.4572)
			(stroke
				(width 0.1)
				(type default)
			)
			(layer "F.Fab")
		)
		(fp_line
			(start 0.8636 -0.4572)
			(end 0.8636 -0.406654)
			(stroke
				(width 0.1)
				(type default)
			)
			(layer "F.Fab")
		)
		(pad "1" smd rect
			(at -0.7366 0 180)
			(size 0.7112 0.8128)
			(layers "F.Cu" "F.Mask" "F.Paste")
			(net "P52V_HS1_GATE1_R")
		)
		(pad "2" smd rect
			(at 0.7366 0 180)
			(size 0.7112 0.8128)
			(layers "F.Cu" "F.Mask" "F.Paste")
			(net "P52V_HS1_GATE2")
		)
	)
	(footprint ""
		(layer "F.Cu")
		(at 157.226 -49.911)
		(property "Reference" "PC36"
			(at 0 0 0)
			(layer "F.SilkS")
			(hide yes)
			(effects
				(font
					(size 1.27 1.27)
				)
			)
		)
		(property "Value" ""
			(at 0 0 0)
			(layer "F.Fab")
			(effects
				(font
					(size 1.27 1.27)
				)
			)
		)
		(duplicate_pad_numbers_are_jumpers no)
		(fp_line
			(start -1.524 -0.762)
			(end 1.524 -0.762)
			(stroke
				(width 0.1524)
				(type default)
			)
			(layer "F.SilkS")
		)
		(fp_line
			(start -1.524 0.762)
			(end -1.524 -0.762)
			(stroke
				(width 0.1524)
				(type default)
			)
			(layer "F.SilkS")
		)
		(fp_line
			(start 1.524 -0.762)
			(end 1.524 0.762)
			(stroke
				(width 0.1524)
				(type default)
			)
			(layer "F.SilkS")
		)
		(fp_line
			(start 1.524 0.762)
			(end -1.524 0.762)
			(stroke
				(width 0.1524)
				(type default)
			)
			(layer "F.SilkS")
		)
		(fp_line
			(start -1.1049 -0.724916)
			(end -1.1049 0.724916)
			(stroke
				(width 0.1)
				(type default)
			)
			(layer "F.Fab")
		)
		(fp_line
			(start -1.1049 0.724916)
			(end 1.1049 0.724916)
			(stroke
				(width 0.1)
				(type default)
			)
			(layer "F.Fab")
		)
		(fp_line
			(start 1.1049 -0.724916)
			(end -1.1049 -0.724916)
			(stroke
				(width 0.1)
				(type default)
			)
			(layer "F.Fab")
		)
		(fp_line
			(start 1.1049 0.724916)
			(end 1.1049 -0.724916)
			(stroke
				(width 0.1)
				(type default)
			)
			(layer "F.Fab")
		)
		(pad "1" smd rect
			(at -0.889 0 180)
			(size 1.016 1.27)
			(layers "F.Cu" "F.Mask" "F.Paste")
			(net "P12V_BRICK")
		)
		(pad "2" smd rect
			(at 0.889 0 180)
			(size 1.016 1.27)
			(layers "F.Cu" "F.Mask" "F.Paste")
			(net "GND")
		)
	)
	(footprint ""
		(layer "F.Cu")
		(at 96.012 -8.763)
		(property "Reference" "ME2"
			(at 0 0 0)
			(layer "F.SilkS")
			(hide yes)
			(effects
				(font
					(size 1.27 1.27)
				)
			)
		)
		(property "Value" ""
			(at 0 0 0)
			(layer "F.Fab")
			(effects
				(font
					(size 1.27 1.27)
				)
			)
		)
		(duplicate_pad_numbers_are_jumpers no)
		(fp_poly
			(pts
				(xy 0 -0.5842) (xy 3.3401 -0.5842) (xy 3.3401 0) (xy 0 0)
			)
			(stroke
				(width 0)
				(type default)
			)
			(fill yes)
			(layer "F.SilkS")
		)
		(fp_poly
			(pts
				(xy 1.32715 -3.4417) (xy 2.01295 -3.4417) (xy 2.01295 -3.2512) (xy 1.32715 -3.2512)
			)
			(stroke
				(width 0)
				(type default)
			)
			(fill yes)
			(layer "F.SilkS")
		)
		(fp_poly
			(pts
				(xy -0.070612 -0.681228) (xy -0.197612 -0.820928) (xy 0.852678 -1.91262) (xy 0.728472 -3.29184)
				(xy -0.248412 -4.300728) (xy -0.184912 -4.478528) (xy -0.007112 -4.503928) (xy 0.684022 -3.785616)
				(xy 0.65659 -4.0894) (xy 0.97155 -4.3434) (xy 1.22555 -4.3561) (xy 1.46685 -4.4704) (xy 2.01295 -4.4704)
				(xy 2.15265 -4.4069) (xy 2.44475 -4.191) (xy 2.49555 -4.191) (xy 2.59715 -4.2926) (xy 2.80035 -4.2672)
				(xy 2.88925 -4.1656) (xy 2.88925 -4.029456) (xy 3.345688 -4.503928) (xy 3.523488 -4.478528) (xy 3.586988 -4.300728)
				(xy 2.88925 -3.58013) (xy 2.88925 -3.3147) (xy 2.82575 -3.2385) (xy 2.67335 -3.2385) (xy 2.521966 -1.875282)
				(xy 2.545842 -1.85039)
				(arc
					(start 2.55905 -1.8415)
					(mid 2.648099 -1.766068)
					(end 2.717292 -1.672082)
				)
				(xy 3.536188 -0.820928) (xy 3.409188 -0.681228) (xy 3.244088 -0.693928)
				(arc
					(start 2.737612 -1.216914)
					(mid 2.31728 -0.925553)
					(end 1.86055 -1.1557)
				)
				(xy 0.92075 -1.1557) (xy 0.888492 -1.51384) (xy 0.094488 -0.693928)
			)
			(stroke
				(width 0)
				(type default)
			)
			(fill yes)
			(layer "F.SilkS")
		)
	)
	(footprint ""
		(layer "F.Cu")
		(at 38.90772 -55.20944 -90)
		(property "Reference" "C93"
			(at 0 0 270)
			(layer "F.SilkS")
			(hide yes)
			(effects
				(font
					(size 1.27 1.27)
				)
			)
		)
		(property "Value" ""
			(at 0 0 270)
			(layer "F.Fab")
			(effects
				(font
					(size 1.27 1.27)
				)
			)
		)
		(duplicate_pad_numbers_are_jumpers no)
		(fp_line
			(start -0.7874 0.4064)
			(end -0.7874 -0.4064)
			(stroke
				(width 0.1524)
				(type default)
			)
			(layer "F.SilkS")
		)
		(fp_line
			(start 0.7874 0.4064)
			(end -0.7874 0.4064)
			(stroke
				(width 0.1524)
				(type default)
			)
			(layer "F.SilkS")
		)
		(fp_line
			(start -0.7874 -0.4064)
			(end 0.7874 -0.4064)
			(stroke
				(width 0.1524)
				(type default)
			)
			(layer "F.SilkS")
		)
		(fp_line
			(start 0.7874 -0.4064)
			(end 0.7874 0.4064)
			(stroke
				(width 0.1524)
				(type default)
			)
			(layer "F.SilkS")
		)
		(fp_line
			(start -0.6858 0.3048)
			(end -0.6858 -0.3048)
			(stroke
				(width 0.1)
				(type default)
			)
			(layer "F.Fab")
		)
		(fp_line
			(start -0.1016 0.3048)
			(end -0.6858 0.3048)
			(stroke
				(width 0.1)
				(type default)
			)
			(layer "F.Fab")
		)
		(fp_line
			(start 0.1016 0.3048)
			(end 0.1016 0.2794)
			(stroke
				(width 0.1)
				(type default)
			)
			(layer "F.Fab")
		)
		(fp_line
			(start 0.6858 0.3048)
			(end 0.1016 0.3048)
			(stroke
				(width 0.1)
				(type default)
			)
			(layer "F.Fab")
		)
		(fp_line
			(start -0.1016 0.2794)
			(end -0.1016 0.3048)
			(stroke
				(width 0.1)
				(type default)
			)
			(layer "F.Fab")
		)
		(fp_line
			(start 0.1016 0.2794)
			(end -0.1016 0.2794)
			(stroke
				(width 0.1)
				(type default)
			)
			(layer "F.Fab")
		)
		(fp_line
			(start -0.1016 -0.2794)
			(end 0.1016 -0.2794)
			(stroke
				(width 0.1)
				(type default)
			)
			(layer "F.Fab")
		)
		(fp_line
			(start 0.1016 -0.2794)
			(end 0.1016 -0.3048)
			(stroke
				(width 0.1)
				(type default)
			)
			(layer "F.Fab")
		)
		(fp_line
			(start -0.6858 -0.3048)
			(end -0.1016 -0.3048)
			(stroke
				(width 0.1)
				(type default)
			)
			(layer "F.Fab")
		)
		(fp_line
			(start -0.1016 -0.3048)
			(end -0.1016 -0.2794)
			(stroke
				(width 0.1)
				(type default)
			)
			(layer "F.Fab")
		)
		(fp_line
			(start 0.1016 -0.3048)
			(end 0.6858 -0.3048)
			(stroke
				(width 0.1)
				(type default)
			)
			(layer "F.Fab")
		)
		(fp_line
			(start 0.6858 -0.3048)
			(end 0.6858 0.3048)
			(stroke
				(width 0.1)
				(type default)
			)
			(layer "F.Fab")
		)
		(pad "1" smd rect
			(at -0.40005 0 90)
			(size 0.4572 0.508)
			(layers "F.Cu" "F.Mask" "F.Paste")
			(net "P12V_HPDB")
		)
		(pad "2" smd rect
			(at 0.40005 0 90)
			(size 0.4572 0.508)
			(layers "F.Cu" "F.Mask" "F.Paste")
			(net "GND")
		)
	)
)
